(kicad_pcb
	(version 20241229)
	(generator "pcbnew")
	(generator_version "9.0")
	(general
		(thickness 1.61)
		(legacy_teardrops no)
	)
	(paper "A3")
	(title_block
		(title "RDIMM DDR5 Tester")
		(date "2026-05-21")
		(rev "2.2.0")
		(company "Antmicro")
		(comment 9 "footprint 119 of 796 (U34), pads 200-265 of 676")
	)
	(layers
		(0 "F.Cu" signal)
		(4 "In1.Cu" power)
		(6 "In2.Cu" mixed)
		(8 "In3.Cu" power)
		(10 "In4.Cu" mixed)
		(12 "In5.Cu" power)
		(14 "In6.Cu" mixed)
		(16 "In7.Cu" power)
		(18 "In8.Cu" power)
		(20 "In9.Cu" mixed)
		(22 "In10.Cu" power)
		(2 "B.Cu" signal)
		(9 "F.Adhes" user "F.Adhesive")
		(11 "B.Adhes" user "B.Adhesive")
		(13 "F.Paste" user)
		(15 "B.Paste" user)
		(5 "F.SilkS" user "F.Silkscreen")
		(7 "B.SilkS" user "B.Silkscreen")
		(1 "F.Mask" user)
		(3 "B.Mask" user)
		(17 "Dwgs.User" user "User.Drawings")
		(19 "Cmts.User" user "User.Comments")
		(21 "Eco1.User" user "User.Eco1")
		(23 "Eco2.User" user "User.Eco2")
		(25 "Edge.Cuts" user)
		(27 "Margin" user)
		(31 "F.CrtYd" user "F.Courtyard")
		(29 "B.CrtYd" user "B.Courtyard")
		(35 "F.Fab" user)
		(33 "B.Fab" user)
	)
	(footprint "antmicro-footprints:BGA-676_27x27mm_Layout26x26_P1x1mm_FFVB676"
		(layer "F.Cu")
		(at 188.5 152.5 90)
		(property "Reference" "U34"
			(at -14.72 12.46 180)
			(layer "F.SilkS")
			(effects
				(font
					(size 0.7 0.7)
					(thickness 0.15)
				)
				(justify left bottom)
			)
		)
		(property "Value" "XCAU25P-2FFVB676I"
			(at 0 15.5 90)
			(layer "F.Fab")
			(effects
				(font
					(size 0.7 0.7)
					(thickness 0.15)
				)
				(justify left bottom)
			)
		)
		(property "Datasheet" "https://docs.xilinx.com/viewer/book-attachment/2PXOpPtpaABIt0fkzeBLnw/hvbsEUaOT0OxFhln7VEVyA"
			(at 0 0 90)
			(layer "F.Fab")
			(hide yes)
			(effects
				(font
					(size 1.27 1.27)
					(thickness 0.15)
				)
			)
		)
		(property "MPN" "XCAU25P-2FFVB676I"
			(at 0 0 90)
			(unlocked yes)
			(layer "F.Fab")
			(hide yes)
			(effects
				(font
					(size 1 1)
					(thickness 0.15)
				)
			)
		)
		(property "Manufacturer" "AMD-Xilinx"
			(at 0 0 90)
			(unlocked yes)
			(layer "F.Fab")
			(hide yes)
			(effects
				(font
					(size 1 1)
					(thickness 0.15)
				)
			)
		)
		(property "Author" "Antmicro"
			(at 0 0 90)
			(unlocked yes)
			(layer "F.Fab")
			(hide yes)
			(effects
				(font
					(size 1 1)
					(thickness 0.15)
				)
			)
		)
		(property "License" "Apache-2.0"
			(at 0 0 90)
			(unlocked yes)
			(layer "F.Fab")
			(hide yes)
			(effects
				(font
					(size 1 1)
					(thickness 0.15)
				)
			)
		)
		(sheetname "/FPGA Config/")
		(sheetfile "fpga-config.kicad_sch")
		(attr smd)
		(pad "B18" smd circle
			(at 4.5 -11.5 90)
			(size 0.5 0.5)
			(layers "F.Cu" "F.Mask" "F.Paste")
			(net 1 "GND")
			(pinfunction "GND")
			(pintype "passive")
			(solder_mask_margin 0.075)
		)
		(pad "B19" smd circle
			(at 5.5 -11.5 90)
			(size 0.5 0.5)
			(layers "F.Cu" "F.Mask" "F.Paste")
			(net 543 "/FPGA banks HP/GCLK_100_LVDS+")
			(pinfunction "IO_L14P_T2L_N2_GC_67")
			(pintype "bidirectional")
			(die_length 14.761)
			(solder_mask_margin 0.075)
		)
		(pad "B20" smd circle
			(at 6.5 -11.5 90)
			(size 0.5 0.5)
			(layers "F.Cu" "F.Mask" "F.Paste")
			(net 544 "/FPGA banks HP/GCLK_100_LVDS-")
			(pinfunction "IO_L14N_T2L_N3_GC_67")
			(pintype "bidirectional")
			(die_length 14.716)
			(solder_mask_margin 0.075)
		)
		(pad "B21" smd circle
			(at 7.5 -11.5 90)
			(size 0.5 0.5)
			(layers "F.Cu" "F.Mask" "F.Paste")
			(net 398 "/Ethernet/ETH.RXC")
			(pinfunction "IO_L22N_T3U_N7_DBC_AD0N_67")
			(pintype "bidirectional")
			(die_length 13.059)
			(solder_mask_margin 0.075)
		)
		(pad "B22" smd circle
			(at 8.5 -11.5 90)
			(size 0.5 0.5)
			(layers "F.Cu" "F.Mask" "F.Paste")
			(net 501 "unconnected-(U34E-IO_L24N_T3U_N11_67-PadB22)")
			(pinfunction "IO_L24N_T3U_N11_67")
			(pintype "bidirectional+no_connect")
			(die_length 12.209)
			(solder_mask_margin 0.075)
		)
		(pad "B23" smd circle
			(at 9.5 -11.5 90)
			(size 0.5 0.5)
			(layers "F.Cu" "F.Mask" "F.Paste")
			(net 1 "GND")
			(pinfunction "GND")
			(pintype "passive")
			(solder_mask_margin 0.075)
		)
		(pad "B24" smd circle
			(at 10.5 -11.5 90)
			(size 0.5 0.5)
			(layers "F.Cu" "F.Mask" "F.Paste")
			(net 399 "/Ethernet/ETH.REF_CLK")
			(pinfunction "IO_L21N_T3L_N5_AD8N_67")
			(pintype "bidirectional")
			(die_length 13.648)
			(solder_mask_margin 0.075)
		)
		(pad "B25" smd circle
			(at 11.5 -11.5 90)
			(size 0.5 0.5)
			(layers "F.Cu" "F.Mask" "F.Paste")
			(net 129 "/DDR5 RDIMM/B.DQ29")
			(pinfunction "IO_L24P_T3U_N10_66")
			(pintype "bidirectional")
			(die_length 17.31)
			(solder_mask_margin 0.075)
		)
		(pad "B26" smd circle
			(at 12.5 -11.5 90)
			(size 0.5 0.5)
			(layers "F.Cu" "F.Mask" "F.Paste")
			(net 128 "/DDR5 RDIMM/B.DQ28")
			(pinfunction "IO_L24N_T3U_N11_66")
			(pintype "bidirectional")
			(die_length 17.349)
			(solder_mask_margin 0.075)
		)
		(pad "C1" smd circle
			(at -12.5 -10.5 90)
			(size 0.5 0.5)
			(layers "F.Cu" "F.Mask" "F.Paste")
			(net 1 "GND")
			(pinfunction "GND")
			(pintype "passive")
			(solder_mask_margin 0.075)
		)
		(pad "C2" smd circle
			(at -11.5 -10.5 90)
			(size 0.5 0.5)
			(layers "F.Cu" "F.Mask" "F.Paste")
			(net 1 "GND")
			(pinfunction "GND")
			(pintype "passive")
			(solder_mask_margin 0.075)
		)
		(pad "C3" smd circle
			(at -10.5 -10.5 90)
			(size 0.5 0.5)
			(layers "F.Cu" "F.Mask" "F.Paste")
			(net 502 "unconnected-(U34L-NC-PadC3)")
			(pinfunction "NC")
			(pintype "no_connect")
			(solder_mask_margin 0.075)
		)
		(pad "C4" smd circle
			(at -9.5 -10.5 90)
			(size 0.5 0.5)
			(layers "F.Cu" "F.Mask" "F.Paste")
			(net 503 "unconnected-(U34L-NC-PadC4)")
			(pinfunction "NC")
			(pintype "no_connect")
			(solder_mask_margin 0.075)
		)
		(pad "C5" smd circle
			(at -8.5 -10.5 90)
			(size 0.5 0.5)
			(layers "F.Cu" "F.Mask" "F.Paste")
			(net 1 "GND")
			(pinfunction "GND")
			(pintype "passive")
			(solder_mask_margin 0.075)
		)
		(pad "C6" smd circle
			(at -7.5 -10.5 90)
			(size 0.5 0.5)
			(layers "F.Cu" "F.Mask" "F.Paste")
			(net 1 "GND")
			(pinfunction "GND")
			(pintype "passive")
			(solder_mask_margin 0.075)
		)
		(pad "C7" smd circle
			(at -6.5 -10.5 90)
			(size 0.5 0.5)
			(layers "F.Cu" "F.Mask" "F.Paste")
			(net 172 "+1V2_MGTAVTT")
			(pinfunction "MGTAVTT_R")
			(pintype "passive")
			(solder_mask_margin 0.075)
		)
		(pad "C8" smd circle
			(at -5.5 -10.5 90)
			(size 0.5 0.5)
			(layers "F.Cu" "F.Mask" "F.Paste")
			(net 1 "GND")
			(pinfunction "GND")
			(pintype "passive")
			(solder_mask_margin 0.075)
		)
		(pad "C9" smd circle
			(at -4.5 -10.5 90)
			(size 0.5 0.5)
			(layers "F.Cu" "F.Mask" "F.Paste")
			(net 388 "/Debug FTDI + VNA/AUX.TCK")
			(pinfunction "IO_L9N_AD3N_86")
			(pintype "bidirectional")
			(die_length 18.411)
			(solder_mask_margin 0.075)
		)
		(pad "C10" smd circle
			(at -3.5 -10.5 90)
			(size 0.5 0.5)
			(layers "F.Cu" "F.Mask" "F.Paste")
			(net 1 "GND")
			(pinfunction "GND")
			(pintype "passive")
			(solder_mask_margin 0.075)
		)
		(pad "C11" smd circle
			(at -2.5 -10.5 90)
			(size 0.5 0.5)
			(layers "F.Cu" "F.Mask" "F.Paste")
			(net 505 "unconnected-(U34G-IO_L12P_AD0P_86-PadC11)")
			(pinfunction "IO_L12P_AD0P_86")
			(pintype "bidirectional+no_connect")
			(die_length 16.261)
			(solder_mask_margin 0.075)
		)
		(pad "C12" smd circle
			(at -1.5 -10.5 90)
			(size 0.5 0.5)
			(layers "F.Cu" "F.Mask" "F.Paste")
			(net 385 "HDMI_OE")
			(pinfunction "IO_L10P_AD10P_87")
			(pintype "bidirectional")
			(die_length 14.414)
			(solder_mask_margin 0.075)
		)
		(pad "C13" smd circle
			(at -0.5 -10.5 90)
			(size 0.5 0.5)
			(layers "F.Cu" "F.Mask" "F.Paste")
			(net 549 "HDMI_OUT_HPD")
			(pinfunction "IO_L9N_AD11N_87")
			(pintype "bidirectional")
			(die_length 13.612)
			(solder_mask_margin 0.075)
		)
		(pad "C14" smd circle
			(at 0.5 -10.5 90)
			(size 0.5 0.5)
			(layers "F.Cu" "F.Mask" "F.Paste")
			(net 768 "/FPGA MGT Interface/HDMI_CTL.SCL")
			(pinfunction "IO_L9P_AD11P_87")
			(pintype "bidirectional")
			(die_length 12.719)
			(solder_mask_margin 0.075)
		)
		(pad "C15" smd circle
			(at 1.5 -10.5 90)
			(size 0.5 0.5)
			(layers "F.Cu" "F.Mask" "F.Paste")
			(net 1 "GND")
			(pinfunction "GND")
			(pintype "passive")
			(solder_mask_margin 0.075)
		)
		(pad "C16" smd circle
			(at 2.5 -10.5 90)
			(size 0.5 0.5)
			(layers "F.Cu" "F.Mask" "F.Paste")
			(net 620 "/FPGA banks HP/HyperRAM.DQ1")
			(pinfunction "IO_L6N_T0U_N11_AD6N_67")
			(pintype "bidirectional")
			(die_length 16.954)
			(solder_mask_margin 0.075)
		)
		(pad "C17" smd circle
			(at 3.5 -10.5 90)
			(size 0.5 0.5)
			(layers "F.Cu" "F.Mask" "F.Paste")
			(net 395 "/Ethernet/ETH.RXD2")
			(pinfunction "IO_L15P_T2L_N4_AD11P_67")
			(pintype "bidirectional")
			(die_length 15.597)
			(solder_mask_margin 0.075)
		)
		(pad "C18" smd circle
			(at 4.5 -10.5 90)
			(size 0.5 0.5)
			(layers "F.Cu" "F.Mask" "F.Paste")
			(net 508 "unconnected-(U34E-IO_L13P_T2L_N0_GC_QBC_67-PadC18)")
			(pinfunction "IO_L13P_T2L_N0_GC_QBC_67")
			(pintype "bidirectional+no_connect")
			(die_length 14.663)
			(solder_mask_margin 0.075)
		)
		(pad "C19" smd circle
			(at 5.5 -10.5 90)
			(size 0.5 0.5)
			(layers "F.Cu" "F.Mask" "F.Paste")
			(net 509 "unconnected-(U34E-IO_L13N_T2L_N1_GC_QBC_67-PadC19)")
			(pinfunction "IO_L13N_T2L_N1_GC_QBC_67")
			(pintype "bidirectional+no_connect")
			(die_length 14.647)
			(solder_mask_margin 0.075)
		)
		(pad "C20" smd circle
			(at 6.5 -10.5 90)
			(size 0.5 0.5)
			(layers "F.Cu" "F.Mask" "F.Paste")
			(net 797 "+1V8")
			(pinfunction "VCCO_67")
			(pintype "power_in")
			(solder_mask_margin 0.075)
		)
		(pad "C21" smd circle
			(at 7.5 -10.5 90)
			(size 0.5 0.5)
			(layers "F.Cu" "F.Mask" "F.Paste")
			(net 397 "/Ethernet/ETH.RX_CTL")
			(pinfunction "IO_L22P_T3U_N6_DBC_AD0P_67")
			(pintype "bidirectional")
			(die_length 13.059)
			(solder_mask_margin 0.075)
		)
		(pad "C22" smd circle
			(at 8.5 -10.5 90)
			(size 0.5 0.5)
			(layers "F.Cu" "F.Mask" "F.Paste")
			(net 410 "/Ethernet/ETH.MDC")
			(pinfunction "IO_L24P_T3U_N10_67")
			(pintype "bidirectional")
			(die_length 11.885)
			(solder_mask_margin 0.075)
		)
		(pad "C23" smd circle
			(at 9.5 -10.5 90)
			(size 0.5 0.5)
			(layers "F.Cu" "F.Mask" "F.Paste")
			(net 401 "/Ethernet/ETH.~{RESET}")
			(pinfunction "IO_L21P_T3L_N4_AD8P_67")
			(pintype "bidirectional")
			(die_length 13.582)
			(solder_mask_margin 0.075)
		)
		(pad "C24" smd circle
			(at 10.5 -10.5 90)
			(size 0.5 0.5)
			(layers "F.Cu" "F.Mask" "F.Paste")
			(net 596 "/DDR5 RDIMM/B.DQS8_N")
			(pinfunction "IO_L22N_T3U_N7_DBC_AD0N_66")
			(pintype "bidirectional")
			(die_length 14.847)
			(solder_mask_margin 0.075)
		)
		(pad "C25" smd circle
			(at 11.5 -10.5 90)
			(size 0.5 0.5)
			(layers "F.Cu" "F.Mask" "F.Paste")
			(net 1 "GND")
			(pinfunction "GND")
			(pintype "passive")
			(solder_mask_margin 0.075)
		)
		(pad "C26" smd circle
			(at 12.5 -10.5 90)
			(size 0.5 0.5)
			(layers "F.Cu" "F.Mask" "F.Paste")
			(net 475 "/DDR5 RDIMM/B.DQ30")
			(pinfunction "IO_L23N_T3U_N9_66")
			(pintype "bidirectional")
			(die_length 17.439)
			(solder_mask_margin 0.075)
		)
		(pad "D1" smd circle
			(at -12.5 -9.5 90)
			(size 0.5 0.5)
			(layers "F.Cu" "F.Mask" "F.Paste")
			(net 510 "unconnected-(U34L-NC-PadD1)")
			(pinfunction "NC")
			(pintype "no_connect")
			(solder_mask_margin 0.075)
		)
		(pad "D2" smd circle
			(at -11.5 -9.5 90)
			(size 0.5 0.5)
			(layers "F.Cu" "F.Mask" "F.Paste")
			(net 511 "unconnected-(U34L-NC-PadD2)")
			(pinfunction "NC")
			(pintype "no_connect")
			(solder_mask_margin 0.075)
		)
		(pad "D3" smd circle
			(at -10.5 -9.5 90)
			(size 0.5 0.5)
			(layers "F.Cu" "F.Mask" "F.Paste")
			(net 1 "GND")
			(pinfunction "GND")
			(pintype "passive")
			(solder_mask_margin 0.075)
		)
		(pad "D4" smd circle
			(at -9.5 -9.5 90)
			(size 0.5 0.5)
			(layers "F.Cu" "F.Mask" "F.Paste")
			(net 1 "GND")
			(pinfunction "GND")
			(pintype "passive")
			(solder_mask_margin 0.075)
		)
		(pad "D5" smd circle
			(at -8.5 -9.5 90)
			(size 0.5 0.5)
			(layers "F.Cu" "F.Mask" "F.Paste")
			(net 1 "GND")
			(pinfunction "GND")
			(pintype "passive")
			(solder_mask_margin 0.075)
		)
		(pad "D6" smd circle
			(at -7.5 -9.5 90)
			(size 0.5 0.5)
			(layers "F.Cu" "F.Mask" "F.Paste")
			(net 512 "unconnected-(U34L-NC-PadD6)")
			(pinfunction "NC")
			(pintype "no_connect")
			(solder_mask_margin 0.075)
		)
		(pad "D7" smd circle
			(at -6.5 -9.5 90)
			(size 0.5 0.5)
			(layers "F.Cu" "F.Mask" "F.Paste")
			(net 513 "unconnected-(U34L-NC-PadD7)")
			(pinfunction "NC")
			(pintype "no_connect")
			(solder_mask_margin 0.075)
		)
		(pad "D8" smd circle
			(at -5.5 -9.5 90)
			(size 0.5 0.5)
			(layers "F.Cu" "F.Mask" "F.Paste")
			(net 1 "GND")
			(pinfunction "GND")
			(pintype "passive")
			(solder_mask_margin 0.075)
		)
		(pad "D9" smd circle
			(at -4.5 -9.5 90)
			(size 0.5 0.5)
			(layers "F.Cu" "F.Mask" "F.Paste")
			(net 408 "/Debug FTDI + VNA/AUX.TMS")
			(pinfunction "IO_L9P_AD3P_86")
			(pintype "bidirectional")
			(die_length 17.841)
			(solder_mask_margin 0.075)
		)
		(pad "D10" smd circle
			(at -3.5 -9.5 90)
			(size 0.5 0.5)
			(layers "F.Cu" "F.Mask" "F.Paste")
			(net 442 "/Debug FTDI + VNA/AUX.RST")
			(pinfunction "IO_L8N_HDGC_AD4N_86")
			(pintype "bidirectional")
			(die_length 16.776)
			(solder_mask_margin 0.075)
		)
		(pad "D11" smd circle
			(at -2.5 -9.5 90)
			(size 0.5 0.5)
			(layers "F.Cu" "F.Mask" "F.Paste")
			(net 514 "unconnected-(U34G-IO_L8P_HDGC_AD4P_86-PadD11)")
			(pinfunction "IO_L8P_HDGC_AD4P_86")
			(pintype "bidirectional+no_connect")
			(die_length 16.7)
			(solder_mask_margin 0.075)
		)
		(pad "D12" smd circle
			(at -1.5 -9.5 90)
			(size 0.5 0.5)
			(layers "F.Cu" "F.Mask" "F.Paste")
			(net 1 "GND")
			(pinfunction "GND")
			(pintype "passive")
			(solder_mask_margin 0.075)
		)
		(pad "D13" smd circle
			(at -0.5 -9.5 90)
			(size 0.5 0.5)
			(layers "F.Cu" "F.Mask" "F.Paste")
			(net 515 "unconnected-(U34H-IO_L8N_HDGC_87-PadD13)")
			(pinfunction "IO_L8N_HDGC_87")
			(pintype "bidirectional+no_connect")
			(die_length 12.81)
			(solder_mask_margin 0.075)
		)
		(pad "D14" smd circle
			(at 0.5 -9.5 90)
			(size 0.5 0.5)
			(layers "F.Cu" "F.Mask" "F.Paste")
			(net 769 "/FPGA MGT Interface/HDMI_CTL.SDA")
			(pinfunction "IO_L8P_HDGC_87")
			(pintype "bidirectional")
			(die_length 12.921)
			(solder_mask_margin 0.075)
		)
		(pad "D15" smd circle
			(at 1.5 -9.5 90)
			(size 0.5 0.5)
			(layers "F.Cu" "F.Mask" "F.Paste")
			(net 613 "/FPGA banks HP/HyperRAM.DQ3")
			(pinfunction "IO_L3N_T0L_N5_AD15N_67")
			(pintype "bidirectional")
			(die_length 16.228)
			(solder_mask_margin 0.075)
		)
		(pad "D16" smd circle
			(at 2.5 -9.5 90)
			(size 0.5 0.5)
			(layers "F.Cu" "F.Mask" "F.Paste")
			(net 614 "/FPGA banks HP/HyperRAM.DQ6")
			(pinfunction "IO_L6P_T0U_N10_AD6P_67")
			(pintype "bidirectional")
			(die_length 16.691)
			(solder_mask_margin 0.075)
		)
		(pad "D17" smd circle
			(at 3.5 -9.5 90)
			(size 0.5 0.5)
			(layers "F.Cu" "F.Mask" "F.Paste")
			(net 797 "+1V8")
			(pinfunction "VCCO_67")
			(pintype "passive")
			(solder_mask_margin 0.075)
		)
		(pad "D18" smd circle
			(at 4.5 -9.5 90)
			(size 0.5 0.5)
			(layers "F.Cu" "F.Mask" "F.Paste")
			(net 643 "unconnected-(U34E-IO_L11N_T1U_N9_GC_67-PadD18)")
			(pinfunction "IO_L11N_T1U_N9_GC_67")
			(pintype "bidirectional+no_connect")
			(die_length 13.119)
			(solder_mask_margin 0.075)
		)
		(pad "D19" smd circle
			(at 5.5 -9.5 90)
			(size 0.5 0.5)
			(layers "F.Cu" "F.Mask" "F.Paste")
			(net 403 "HDMI_REC_CLK_P")
			(pinfunction "IO_L12P_T1U_N10_GC_67")
			(pintype "bidirectional")
			(die_length 14.406)
			(solder_mask_margin 0.075)
		)
		(pad "D20" smd circle
			(at 6.5 -9.5 90)
			(size 0.5 0.5)
			(layers "F.Cu" "F.Mask" "F.Paste")
			(net 458 "HDMI_REC_CLK_N")
			(pinfunction "IO_L12N_T1U_N11_GC_67")
			(pintype "bidirectional")
			(die_length 14.428)
			(solder_mask_margin 0.075)
		)
		(pad "D21" smd circle
			(at 7.5 -9.5 90)
			(size 0.5 0.5)
			(layers "F.Cu" "F.Mask" "F.Paste")
			(net 435 "/Ethernet/ETH.TX_CTL")
			(pinfunction "IO_L20N_T3L_N3_AD1N_67")
			(pintype "bidirectional")
			(die_length 11.044)
			(solder_mask_margin 0.075)
		)
		(pad "D22" smd circle
			(at 8.5 -9.5 90)
			(size 0.5 0.5)
			(layers "F.Cu" "F.Mask" "F.Paste")
			(net 1 "GND")
			(pinfunction "GND")
			(pintype "passive")
			(solder_mask_margin 0.075)
		)
		(pad "D23" smd circle
			(at 9.5 -9.5 90)
			(size 0.5 0.5)
			(layers "F.Cu" "F.Mask" "F.Paste")
			(net 597 "/DDR5 RDIMM/B.DQS8_P")
			(pinfunction "IO_L22P_T3U_N6_DBC_AD0P_66")
			(pintype "bidirectional")
			(die_length 14.897)
			(solder_mask_margin 0.075)
		)
		(pad "D24" smd circle
			(at 10.5 -9.5 90)
			(size 0.5 0.5)
			(layers "F.Cu" "F.Mask" "F.Paste")
			(net 125 "/DDR5 RDIMM/B.DQ25")
			(pinfunction "IO_L21P_T3L_N4_AD8P_66")
			(pintype "bidirectional")
			(die_length 15.819)
			(solder_mask_margin 0.075)
		)
		(pad "D25" smd circle
			(at 11.5 -9.5 90)
			(size 0.5 0.5)
			(layers "F.Cu" "F.Mask" "F.Paste")
			(net 456 "/DDR5 RDIMM/B.DQ27")
			(pinfunction "IO_L21N_T3L_N5_AD8N_66")
			(pintype "bidirectional")
			(die_length 16.046)
			(solder_mask_margin 0.075)
		)
		(pad "D26" smd circle
			(at 12.5 -9.5 90)
			(size 0.5 0.5)
			(layers "F.Cu" "F.Mask" "F.Paste")
			(net 476 "/DDR5 RDIMM/B.DQ31")
			(pinfunction "IO_L23P_T3U_N8_66")
			(pintype "bidirectional")
			(die_length 17.602)
			(solder_mask_margin 0.075)
		)
		(pad "E1" smd circle
			(at -12.5 -8.5 90)
			(size 0.5 0.5)
			(layers "F.Cu" "F.Mask" "F.Paste")
			(net 1 "GND")
			(pinfunction "GND")
			(pintype "passive")
			(solder_mask_margin 0.075)
		)
		(pad "E2" smd circle
			(at -11.5 -8.5 90)
			(size 0.5 0.5)
			(layers "F.Cu" "F.Mask" "F.Paste")
			(net 1 "GND")
			(pinfunction "GND")
			(pintype "passive")
			(solder_mask_margin 0.075)
		)
		(pad "E3" smd circle
			(at -10.5 -8.5 90)
			(size 0.5 0.5)
			(layers "F.Cu" "F.Mask" "F.Paste")
			(net 1 "GND")
			(pinfunction "GND")
			(pintype "passive")
			(solder_mask_margin 0.075)
		)
		(pad "E4" smd circle
			(at -9.5 -8.5 90)
			(size 0.5 0.5)
			(layers "F.Cu" "F.Mask" "F.Paste")
			(net 516 "unconnected-(U34L-NC-PadE4)")
			(pinfunction "NC")
			(pintype "no_connect")
			(solder_mask_margin 0.075)
		)
		(pad "E5" smd circle
			(at -8.5 -8.5 90)
			(size 0.5 0.5)
			(layers "F.Cu" "F.Mask" "F.Paste")
			(net 517 "unconnected-(U34L-NC-PadE5)")
			(pinfunction "NC")
			(pintype "no_connect")
			(solder_mask_margin 0.075)
		)
	)
)
